;EXTENTS: -25.000 -25.000 55.000  55.000  
;LEADER: 12 
;HEADER: 
;CODE  : ASCII 
;FILE  : D:/<user>/F0T/9048_F0T_Management_Board_D/brd/1213/12092022_DA0F0TMDCD0_F0T_Management_Board_D_artwork/9048_F0T_Management_Board_D_brd_V04_1213_1625_1-12.rou for board D:/<user>/F0T/9048_F0T_Management_Board_D/brd/1213/12092022_DA0F0TMDCD0_F0T_Management_Board_D_artwork/#Taaaacb32600.tmp, layers TOP to BOTTOM
%
G90
F1
M16
T01
M16
G00X0105315Y0183421
G40
M15
G01X0105315Y0189721
M16
G40
M30
